(kicad_pcb
	(version 20260206)
	(generator "pcbnew")
	(generator_version "10.0")
	(general
		(thickness 1.6)
		(legacy_teardrops no)
	)
	(paper "A4")
	(title_block
		(title "04192023_DAF0TMB3IC0_F0TG_MB_C_brd_V02_OCP.brd")
		(comment 1 "Grand Teton / footprints 1172-1177 of 8354")
	)
	(layers
		(0 "F.Cu" signal "TOP")
		(4 "In1.Cu" signal "GND")
		(6 "In2.Cu" signal "IN1")
		(8 "In3.Cu" signal "GND1")
		(10 "In4.Cu" signal "IN2")
		(12 "In5.Cu" signal "GND2")
		(14 "In6.Cu" signal "IN3")
		(16 "In7.Cu" signal "GND3")
		(18 "In8.Cu" signal "VCC")
		(20 "In9.Cu" signal "VCC1")
		(22 "In10.Cu" signal "GND4")
		(24 "In11.Cu" signal "IN4")
		(26 "In12.Cu" signal "GND5")
		(28 "In13.Cu" signal "IN5")
		(30 "In14.Cu" signal "GND6")
		(32 "In15.Cu" signal "IN6")
		(34 "In16.Cu" signal "GND7")
		(2 "B.Cu" signal "BOTTOM")
		(9 "F.Adhes" user "F.Adhesive")
		(11 "B.Adhes" user "B.Adhesive")
		(13 "F.Paste" user "Package Geometry/Pastemask Top")
		(15 "B.Paste" user "Package Geometry/Pastemask Bottom")
		(5 "F.SilkS" user "Ref Des/Silkscreen Top")
		(7 "B.SilkS" user "Ref Des/Silkscreen Bottom")
		(1 "F.Mask" user "Board Geometry/Soldermask Top")
		(3 "B.Mask" user "Board Geometry/Soldermask Bottom")
		(17 "Dwgs.User" user "User.Drawings")
		(19 "Cmts.User" user "User.Comments")
		(21 "Eco1.User" user "User.Eco1")
		(23 "Eco2.User" user "User.Eco2")
		(25 "Edge.Cuts" user "Board Geometry/Outline")
		(27 "Margin" user)
		(31 "F.CrtYd" user "Package Geometry/Place Bound Top")
		(29 "B.CrtYd" user "Package Geometry/Place Bound Bottom")
		(35 "F.Fab" user "Ref Des/Assembly Top")
		(33 "B.Fab" user "Ref Des/Assembly Bottom")
	)
	(footprint ""
		(layer "F.Cu")
		(at 267.869924 -419.648386 -90)
		(property "Reference" "U290"
			(at 3.294888 1.383538 0)
			(unlocked yes)
			(layer "F.SilkS")
			(effects
				(font
					(size 0.7874 0.5842)
					(thickness 0.1524)
				)
				(justify left)
			)
		)
		(property "Value" ""
			(at 0 0 270)
			(layer "F.Fab")
			(effects
				(font
					(size 1.27 1.27)
				)
			)
		)
		(duplicate_pad_numbers_are_jumpers no)
		(fp_line
			(start -1.603248 1.500124)
			(end -1.603248 -1.500124)
			(stroke
				(width 0.1524)
				(type default)
			)
			(layer "F.SilkS")
		)
		(fp_line
			(start 1.603248 1.500124)
			(end -1.603248 1.500124)
			(stroke
				(width 0.1524)
				(type default)
			)
			(layer "F.SilkS")
		)
		(fp_line
			(start -1.603248 -1.500124)
			(end 1.603248 -1.500124)
			(stroke
				(width 0.1524)
				(type default)
			)
			(layer "F.SilkS")
		)
		(fp_line
			(start 1.603248 -1.500124)
			(end 1.603248 1.500124)
			(stroke
				(width 0.1524)
				(type default)
			)
			(layer "F.SilkS")
		)
		(fp_line
			(start -0.700024 1.500124)
			(end 0.700024 1.500124)
			(stroke
				(width 0.1)
				(type default)
			)
			(layer "F.Fab")
		)
		(fp_line
			(start 0.700024 1.500124)
			(end 0.700024 0.219964)
			(stroke
				(width 0.1)
				(type default)
			)
			(layer "F.Fab")
		)
		(fp_line
			(start -1.249934 1.169924)
			(end -0.700024 1.169924)
			(stroke
				(width 0.1)
				(type default)
			)
			(layer "F.Fab")
		)
		(fp_line
			(start -0.700024 1.169924)
			(end -0.700024 1.500124)
			(stroke
				(width 0.1)
				(type default)
			)
			(layer "F.Fab")
		)
		(fp_line
			(start -1.249934 0.729996)
			(end -1.249934 1.169924)
			(stroke
				(width 0.1)
				(type default)
			)
			(layer "F.Fab")
		)
		(fp_line
			(start -0.6985 0.729996)
			(end -1.249934 0.729996)
			(stroke
				(width 0.1)
				(type default)
			)
			(layer "F.Fab")
		)
		(fp_line
			(start 0.700024 0.219964)
			(end 1.249934 0.219964)
			(stroke
				(width 0.1)
				(type default)
			)
			(layer "F.Fab")
		)
		(fp_line
			(start 1.249934 0.219964)
			(end 1.249934 -0.219964)
			(stroke
				(width 0.1)
				(type default)
			)
			(layer "F.Fab")
		)
		(fp_line
			(start 0.700024 -0.219964)
			(end 0.700024 -1.500124)
			(stroke
				(width 0.1)
				(type default)
			)
			(layer "F.Fab")
		)
		(fp_line
			(start 1.249934 -0.219964)
			(end 0.700024 -0.219964)
			(stroke
				(width 0.1)
				(type default)
			)
			(layer "F.Fab")
		)
		(fp_line
			(start -1.249934 -0.729996)
			(end -0.6985 -0.729996)
			(stroke
				(width 0.1)
				(type default)
			)
			(layer "F.Fab")
		)
		(fp_line
			(start -0.6985 -0.729996)
			(end -0.6985 0.729996)
			(stroke
				(width 0.1)
				(type default)
			)
			(layer "F.Fab")
		)
		(fp_line
			(start -1.249934 -1.169924)
			(end -1.249934 -0.729996)
			(stroke
				(width 0.1)
				(type default)
			)
			(layer "F.Fab")
		)
		(fp_line
			(start -0.700024 -1.169924)
			(end -1.249934 -1.169924)
			(stroke
				(width 0.1)
				(type default)
			)
			(layer "F.Fab")
		)
		(fp_line
			(start -0.700024 -1.500124)
			(end -0.700024 -1.169924)
			(stroke
				(width 0.1)
				(type default)
			)
			(layer "F.Fab")
		)
		(fp_line
			(start 0.700024 -1.500124)
			(end -0.700024 -1.500124)
			(stroke
				(width 0.1)
				(type default)
			)
			(layer "F.Fab")
		)
		(fp_rect
			(start -0.700024 1.500124)
			(end 0.700024 -1.500124)
			(stroke
				(width 0)
				(type default)
			)
			(fill no)
			(layer "F.Fab")
		)
		(pad "D" smd rect
			(at 0.999998 0 180)
			(size 0.8128 0.9144)
			(layers "F.Cu" "F.Mask" "F.Paste")
			(net "HSC_EN")
		)
		(pad "G" smd rect
			(at -0.999998 -0.94996 180)
			(size 0.8128 0.9144)
			(layers "F.Cu" "F.Mask" "F.Paste")
			(net "PDB_PRSNT_R_N")
		)
		(pad "S" smd rect
			(at -0.999998 0.94996 180)
			(size 0.8128 0.9144)
			(layers "F.Cu" "F.Mask" "F.Paste")
			(net "GND")
		)
	)
	(footprint ""
		(layer "F.Cu")
		(at 134.112 -109.855)
		(property "Reference" "R8117"
			(at 0 0 0)
			(layer "F.SilkS")
			(hide yes)
			(effects
				(font
					(size 1.27 1.27)
				)
			)
		)
		(property "Value" ""
			(at 0 0 0)
			(layer "F.Fab")
			(effects
				(font
					(size 1.27 1.27)
				)
			)
		)
		(duplicate_pad_numbers_are_jumpers no)
		(fp_line
			(start -0.7874 -0.4064)
			(end 0.7874 -0.4064)
			(stroke
				(width 0.1524)
				(type default)
			)
			(layer "F.SilkS")
		)
		(fp_line
			(start -0.7874 0.4064)
			(end -0.7874 -0.4064)
			(stroke
				(width 0.1524)
				(type default)
			)
			(layer "F.SilkS")
		)
		(fp_line
			(start 0.7874 -0.4064)
			(end 0.7874 0.4064)
			(stroke
				(width 0.1524)
				(type default)
			)
			(layer "F.SilkS")
		)
		(fp_line
			(start 0.7874 0.4064)
			(end -0.7874 0.4064)
			(stroke
				(width 0.1524)
				(type default)
			)
			(layer "F.SilkS")
		)
		(fp_line
			(start -0.67945 -0.305054)
			(end -0.12065 -0.305054)
			(stroke
				(width 0.1)
				(type default)
			)
			(layer "F.Fab")
		)
		(fp_line
			(start -0.67945 0.3048)
			(end -0.67945 -0.305054)
			(stroke
				(width 0.1)
				(type default)
			)
			(layer "F.Fab")
		)
		(fp_line
			(start -0.12065 -0.305054)
			(end -0.12065 -0.2794)
			(stroke
				(width 0.1)
				(type default)
			)
			(layer "F.Fab")
		)
		(fp_line
			(start -0.12065 -0.2794)
			(end 0.12065 -0.2794)
			(stroke
				(width 0.1)
				(type default)
			)
			(layer "F.Fab")
		)
		(fp_line
			(start -0.12065 0.2794)
			(end -0.12065 0.3048)
			(stroke
				(width 0.1)
				(type default)
			)
			(layer "F.Fab")
		)
		(fp_line
			(start -0.12065 0.3048)
			(end -0.67945 0.3048)
			(stroke
				(width 0.1)
				(type default)
			)
			(layer "F.Fab")
		)
		(fp_line
			(start 0.120396 0.2794)
			(end -0.12065 0.2794)
			(stroke
				(width 0.1)
				(type default)
			)
			(layer "F.Fab")
		)
		(fp_line
			(start 0.120396 0.3048)
			(end 0.120396 0.2794)
			(stroke
				(width 0.1)
				(type default)
			)
			(layer "F.Fab")
		)
		(fp_line
			(start 0.12065 -0.3048)
			(end 0.67945 -0.3048)
			(stroke
				(width 0.1)
				(type default)
			)
			(layer "F.Fab")
		)
		(fp_line
			(start 0.12065 -0.2794)
			(end 0.12065 -0.3048)
			(stroke
				(width 0.1)
				(type default)
			)
			(layer "F.Fab")
		)
		(fp_line
			(start 0.67945 -0.3048)
			(end 0.67945 0.3048)
			(stroke
				(width 0.1)
				(type default)
			)
			(layer "F.Fab")
		)
		(fp_line
			(start 0.67945 0.3048)
			(end 0.120396 0.3048)
			(stroke
				(width 0.1)
				(type default)
			)
			(layer "F.Fab")
		)
		(pad "1" smd circle
			(at -0.40005 0)
			(size 0 0)
			(layers "F.Cu" "F.Mask" "F.Paste")
			(net "P12V_AUX_UV_ADR_TRIGGER")
		)
		(pad "2" smd circle
			(at 0.40005 0)
			(size 0 0)
			(layers "F.Cu" "F.Mask" "F.Paste")
			(net "FM_UV_ADR_TRIGGER_N_R2")
		)
	)
	(footprint ""
		(layer "F.Cu")
		(at 393.762484 -393.47648 180)
		(property "Reference" "L30"
			(at 0 0 180)
			(layer "F.SilkS")
			(hide yes)
			(effects
				(font
					(size 1.27 1.27)
				)
			)
		)
		(property "Value" ""
			(at 0 0 180)
			(layer "F.Fab")
			(effects
				(font
					(size 1.27 1.27)
				)
			)
		)
		(duplicate_pad_numbers_are_jumpers no)
		(fp_line
			(start 0.762 0.381)
			(end -0.762 0.381)
			(stroke
				(width 0.1524)
				(type default)
			)
			(layer "F.SilkS")
		)
		(fp_line
			(start 0.762 -0.381)
			(end 0.762 0.381)
			(stroke
				(width 0.1524)
				(type default)
			)
			(layer "F.SilkS")
		)
		(fp_line
			(start -0.762 0.381)
			(end -0.762 -0.381)
			(stroke
				(width 0.1524)
				(type default)
			)
			(layer "F.SilkS")
		)
		(fp_line
			(start -0.762 -0.381)
			(end 0.762 -0.381)
			(stroke
				(width 0.1524)
				(type default)
			)
			(layer "F.SilkS")
		)
		(fp_line
			(start 0.680466 0.306324)
			(end 0.118364 0.306324)
			(stroke
				(width 0.1)
				(type default)
			)
			(layer "F.Fab")
		)
		(fp_line
			(start 0.680466 -0.306324)
			(end 0.680466 0.306324)
			(stroke
				(width 0.1)
				(type default)
			)
			(layer "F.Fab")
		)
		(fp_line
			(start 0.118872 -0.2794)
			(end 0.118872 -0.306324)
			(stroke
				(width 0.1)
				(type default)
			)
			(layer "F.Fab")
		)
		(fp_line
			(start 0.118872 -0.306324)
			(end 0.680466 -0.306324)
			(stroke
				(width 0.1)
				(type default)
			)
			(layer "F.Fab")
		)
		(fp_line
			(start 0.118364 0.306324)
			(end 0.118364 0.2794)
			(stroke
				(width 0.1)
				(type default)
			)
			(layer "F.Fab")
		)
		(fp_line
			(start 0.118364 0.2794)
			(end -0.119634 0.2794)
			(stroke
				(width 0.1)
				(type default)
			)
			(layer "F.Fab")
		)
		(fp_line
			(start -0.118364 -0.2794)
			(end 0.118872 -0.2794)
			(stroke
				(width 0.1)
				(type default)
			)
			(layer "F.Fab")
		)
		(fp_line
			(start -0.118364 -0.307086)
			(end -0.118364 -0.2794)
			(stroke
				(width 0.1)
				(type default)
			)
			(layer "F.Fab")
		)
		(fp_line
			(start -0.119634 0.30607)
			(end -0.681736 0.30607)
			(stroke
				(width 0.1)
				(type default)
			)
			(layer "F.Fab")
		)
		(fp_line
			(start -0.119634 0.2794)
			(end -0.119634 0.30607)
			(stroke
				(width 0.1)
				(type default)
			)
			(layer "F.Fab")
		)
		(fp_line
			(start -0.681736 0.30607)
			(end -0.681736 -0.307086)
			(stroke
				(width 0.1)
				(type default)
			)
			(layer "F.Fab")
		)
		(fp_line
			(start -0.681736 -0.307086)
			(end -0.118364 -0.307086)
			(stroke
				(width 0.1)
				(type default)
			)
			(layer "F.Fab")
		)
		(pad "1" smd rect
			(at -0.40005 0)
			(size 0.4572 0.508)
			(layers "F.Cu" "F.Mask" "F.Paste")
			(net "P1V8_CPU0_RT_1D")
		)
		(pad "2" smd rect
			(at 0.40005 0)
			(size 0.4572 0.508)
			(layers "F.Cu" "F.Mask" "F.Paste")
			(net "P1V8_CPU0_RT3_1A_1D")
		)
	)
	(footprint ""
		(layer "F.Cu")
		(at 68.961 -54.61)
		(property "Reference" "R1178"
			(at 0 0 0)
			(layer "F.SilkS")
			(hide yes)
			(effects
				(font
					(size 1.27 1.27)
				)
			)
		)
		(property "Value" ""
			(at 0 0 0)
			(layer "F.Fab")
			(effects
				(font
					(size 1.27 1.27)
				)
			)
		)
		(duplicate_pad_numbers_are_jumpers no)
		(fp_line
			(start -0.7874 -0.4064)
			(end 0.7874 -0.4064)
			(stroke
				(width 0.1524)
				(type default)
			)
			(layer "F.SilkS")
		)
		(fp_line
			(start -0.7874 0.4064)
			(end -0.7874 -0.4064)
			(stroke
				(width 0.1524)
				(type default)
			)
			(layer "F.SilkS")
		)
		(fp_line
			(start 0.7874 -0.4064)
			(end 0.7874 0.4064)
			(stroke
				(width 0.1524)
				(type default)
			)
			(layer "F.SilkS")
		)
		(fp_line
			(start 0.7874 0.4064)
			(end -0.7874 0.4064)
			(stroke
				(width 0.1524)
				(type default)
			)
			(layer "F.SilkS")
		)
		(fp_line
			(start -0.67945 -0.305054)
			(end -0.12065 -0.305054)
			(stroke
				(width 0.1)
				(type default)
			)
			(layer "F.Fab")
		)
		(fp_line
			(start -0.67945 0.3048)
			(end -0.67945 -0.305054)
			(stroke
				(width 0.1)
				(type default)
			)
			(layer "F.Fab")
		)
		(fp_line
			(start -0.12065 -0.305054)
			(end -0.12065 -0.2794)
			(stroke
				(width 0.1)
				(type default)
			)
			(layer "F.Fab")
		)
		(fp_line
			(start -0.12065 -0.2794)
			(end 0.12065 -0.2794)
			(stroke
				(width 0.1)
				(type default)
			)
			(layer "F.Fab")
		)
		(fp_line
			(start -0.12065 0.2794)
			(end -0.12065 0.3048)
			(stroke
				(width 0.1)
				(type default)
			)
			(layer "F.Fab")
		)
		(fp_line
			(start -0.12065 0.3048)
			(end -0.67945 0.3048)
			(stroke
				(width 0.1)
				(type default)
			)
			(layer "F.Fab")
		)
		(fp_line
			(start 0.120396 0.2794)
			(end -0.12065 0.2794)
			(stroke
				(width 0.1)
				(type default)
			)
			(layer "F.Fab")
		)
		(fp_line
			(start 0.120396 0.3048)
			(end 0.120396 0.2794)
			(stroke
				(width 0.1)
				(type default)
			)
			(layer "F.Fab")
		)
		(fp_line
			(start 0.12065 -0.3048)
			(end 0.67945 -0.3048)
			(stroke
				(width 0.1)
				(type default)
			)
			(layer "F.Fab")
		)
		(fp_line
			(start 0.12065 -0.2794)
			(end 0.12065 -0.3048)
			(stroke
				(width 0.1)
				(type default)
			)
			(layer "F.Fab")
		)
		(fp_line
			(start 0.67945 -0.3048)
			(end 0.67945 0.3048)
			(stroke
				(width 0.1)
				(type default)
			)
			(layer "F.Fab")
		)
		(fp_line
			(start 0.67945 0.3048)
			(end 0.120396 0.3048)
			(stroke
				(width 0.1)
				(type default)
			)
			(layer "F.Fab")
		)
		(pad "1" smd circle
			(at -0.40005 0)
			(size 0 0)
			(layers "F.Cu" "F.Mask" "F.Paste")
			(net "OCP_V3_2_P3V3_R3_PWRGD")
		)
		(pad "2" smd circle
			(at 0.40005 0)
			(size 0 0)
			(layers "F.Cu" "F.Mask" "F.Paste")
			(net "HP_LVC3_OCP_V3_2_PWRGD_R1")
		)
	)
	(footprint ""
		(layer "F.Cu")
		(at 120.395238 -41.17975 -90)
		(property "Reference" "R6279"
			(at 0 0 270)
			(layer "F.SilkS")
			(hide yes)
			(effects
				(font
					(size 1.27 1.27)
				)
			)
		)
		(property "Value" ""
			(at 0 0 270)
			(layer "F.Fab")
			(effects
				(font
					(size 1.27 1.27)
				)
			)
		)
		(duplicate_pad_numbers_are_jumpers no)
		(fp_line
			(start -0.7874 0.4064)
			(end -0.7874 -0.4064)
			(stroke
				(width 0.1524)
				(type default)
			)
			(layer "F.SilkS")
		)
		(fp_line
			(start 0.7874 0.4064)
			(end -0.7874 0.4064)
			(stroke
				(width 0.1524)
				(type default)
			)
			(layer "F.SilkS")
		)
		(fp_line
			(start -0.7874 -0.4064)
			(end 0.7874 -0.4064)
			(stroke
				(width 0.1524)
				(type default)
			)
			(layer "F.SilkS")
		)
		(fp_line
			(start 0.7874 -0.4064)
			(end 0.7874 0.4064)
			(stroke
				(width 0.1524)
				(type default)
			)
			(layer "F.SilkS")
		)
		(fp_line
			(start -0.67945 0.3048)
			(end -0.67945 -0.305054)
			(stroke
				(width 0.1)
				(type default)
			)
			(layer "F.Fab")
		)
		(fp_line
			(start -0.12065 0.3048)
			(end -0.67945 0.3048)
			(stroke
				(width 0.1)
				(type default)
			)
			(layer "F.Fab")
		)
		(fp_line
			(start 0.120396 0.3048)
			(end 0.120396 0.2794)
			(stroke
				(width 0.1)
				(type default)
			)
			(layer "F.Fab")
		)
		(fp_line
			(start 0.67945 0.3048)
			(end 0.120396 0.3048)
			(stroke
				(width 0.1)
				(type default)
			)
			(layer "F.Fab")
		)
		(fp_line
			(start -0.12065 0.2794)
			(end -0.12065 0.3048)
			(stroke
				(width 0.1)
				(type default)
			)
			(layer "F.Fab")
		)
		(fp_line
			(start 0.120396 0.2794)
			(end -0.12065 0.2794)
			(stroke
				(width 0.1)
				(type default)
			)
			(layer "F.Fab")
		)
		(fp_line
			(start -0.12065 -0.2794)
			(end 0.12065 -0.2794)
			(stroke
				(width 0.1)
				(type default)
			)
			(layer "F.Fab")
		)
		(fp_line
			(start 0.12065 -0.2794)
			(end 0.12065 -0.3048)
			(stroke
				(width 0.1)
				(type default)
			)
			(layer "F.Fab")
		)
		(fp_line
			(start 0.12065 -0.3048)
			(end 0.67945 -0.3048)
			(stroke
				(width 0.1)
				(type default)
			)
			(layer "F.Fab")
		)
		(fp_line
			(start 0.67945 -0.3048)
			(end 0.67945 0.3048)
			(stroke
				(width 0.1)
				(type default)
			)
			(layer "F.Fab")
		)
		(fp_line
			(start -0.67945 -0.305054)
			(end -0.12065 -0.305054)
			(stroke
				(width 0.1)
				(type default)
			)
			(layer "F.Fab")
		)
		(fp_line
			(start -0.12065 -0.305054)
			(end -0.12065 -0.2794)
			(stroke
				(width 0.1)
				(type default)
			)
			(layer "F.Fab")
		)
		(pad "1" smd circle
			(at -0.40005 0 270)
			(size 0 0)
			(layers "F.Cu" "F.Mask" "F.Paste")
			(net "SMB_USB_CPU0_HUB1_SDA")
		)
		(pad "2" smd circle
			(at 0.40005 0 270)
			(size 0 0)
			(layers "F.Cu" "F.Mask" "F.Paste")
			(net "SMB_USB_HUB2_TI_SDA_MRP_PRT_CTL2")
		)
	)
	(footprint ""
		(layer "F.Cu")
		(at 110.85703 -257.74523)
		(property "Reference" "C2427"
			(at 0 0 0)
			(layer "F.SilkS")
			(hide yes)
			(effects
				(font
					(size 1.27 1.27)
				)
			)
		)
		(property "Value" ""
			(at 0 0 0)
			(layer "F.Fab")
			(effects
				(font
					(size 1.27 1.27)
				)
			)
		)
		(duplicate_pad_numbers_are_jumpers no)
		(fp_line
			(start -0.7874 -0.4064)
			(end 0.7874 -0.4064)
			(stroke
				(width 0.1524)
				(type default)
			)
			(layer "F.SilkS")
		)
		(fp_line
			(start -0.7874 0.4064)
			(end -0.7874 -0.4064)
			(stroke
				(width 0.1524)
				(type default)
			)
			(layer "F.SilkS")
		)
		(fp_line
			(start 0.7874 -0.4064)
			(end 0.7874 0.4064)
			(stroke
				(width 0.1524)
				(type default)
			)
			(layer "F.SilkS")
		)
		(fp_line
			(start 0.7874 0.4064)
			(end -0.7874 0.4064)
			(stroke
				(width 0.1524)
				(type default)
			)
			(layer "F.SilkS")
		)
		(fp_line
			(start -0.67945 -0.305054)
			(end -0.12065 -0.305054)
			(stroke
				(width 0.1)
				(type default)
			)
			(layer "F.Fab")
		)
		(fp_line
			(start -0.67945 0.3048)
			(end -0.67945 -0.305054)
			(stroke
				(width 0.1)
				(type default)
			)
			(layer "F.Fab")
		)
		(fp_line
			(start -0.12065 -0.305054)
			(end -0.12065 -0.2794)
			(stroke
				(width 0.1)
				(type default)
			)
			(layer "F.Fab")
		)
		(fp_line
			(start -0.12065 -0.2794)
			(end 0.12065 -0.2794)
			(stroke
				(width 0.1)
				(type default)
			)
			(layer "F.Fab")
		)
		(fp_line
			(start -0.12065 0.2794)
			(end -0.12065 0.3048)
			(stroke
				(width 0.1)
				(type default)
			)
			(layer "F.Fab")
		)
		(fp_line
			(start -0.12065 0.3048)
			(end -0.67945 0.3048)
			(stroke
				(width 0.1)
				(type default)
			)
			(layer "F.Fab")
		)
		(fp_line
			(start 0.120396 0.2794)
			(end -0.12065 0.2794)
			(stroke
				(width 0.1)
				(type default)
			)
			(layer "F.Fab")
		)
		(fp_line
			(start 0.120396 0.3048)
			(end 0.120396 0.2794)
			(stroke
				(width 0.1)
				(type default)
			)
			(layer "F.Fab")
		)
		(fp_line
			(start 0.12065 -0.3048)
			(end 0.67945 -0.3048)
			(stroke
				(width 0.1)
				(type default)
			)
			(layer "F.Fab")
		)
		(fp_line
			(start 0.12065 -0.2794)
			(end 0.12065 -0.3048)
			(stroke
				(width 0.1)
				(type default)
			)
			(layer "F.Fab")
		)
		(fp_line
			(start 0.67945 -0.3048)
			(end 0.67945 0.3048)
			(stroke
				(width 0.1)
				(type default)
			)
			(layer "F.Fab")
		)
		(fp_line
			(start 0.67945 0.3048)
			(end 0.120396 0.3048)
			(stroke
				(width 0.1)
				(type default)
			)
			(layer "F.Fab")
		)
		(pad "1" smd circle
			(at -0.40005 0)
			(size 0 0)
			(layers "F.Cu" "F.Mask" "F.Paste")
			(net "PVDDCR_SOC_P1")
		)
		(pad "2" smd circle
			(at 0.40005 0)
			(size 0 0)
			(layers "F.Cu" "F.Mask" "F.Paste")
			(net "GND")
		)
	)
)
